#ISCELL
  mstr_misc dns *
  *
#ISCELL
  pure_quanta quanta_title_block_c *
  *
#ISCELL
  standard offpage *
  page138_i1
#CELL
  pure_quanta q_res *
  page138_i10
#CELL
  pure_quanta q_res *
  page138_i11
#ISCELL
  pure_quanta_power p1v0 *
  page138_i12
#CELL
  pure_quanta iml3112y2b000ncg8 *
  page138_i13
#CELL
  pure_quanta q_res *
  page138_i14
#CELL
  pure_quanta q_cap *
  page138_i15
#ISCELL
  pure_quanta_power universal_gnd *
  page138_i16
#CELL
  pure_quanta q_cap *
  page138_i17
#ISCELL
  pure_quanta_power universal_gnd *
  page138_i18
#ISCELL
  standard offpage *
  page138_i19
#ISCELL
  standard offpage *
  page138_i2
#ISCELL
  standard offpage *
  page138_i20
#ISCELL
  standard offpage *
  page138_i21
#ISCELL
  standard offpage *
  page138_i22
#ISCELL
  standard offpage *
  page138_i23
#ISCELL
  standard offpage *
  page138_i24
#CELL
  pure_quanta q_res *
  page138_i25
#CELL
  pure_quanta q_res *
  page138_i26
#CELL
  pure_quanta q_res *
  page138_i27
#CELL
  pure_quanta q_res *
  page138_i28
#ISCELL
  pure_quanta_power universal_gnd *
  page138_i29
#ISCELL
  standard offpage *
  page138_i3
#CELL
  pure_quanta q_res *
  page138_i30
#CELL
  pure_quanta q_res *
  page138_i31
#CELL
  pure_quanta q_res *
  page138_i32
#CELL
  pure_quanta q_res *
  page138_i33
#ISCELL
  pure_quanta_power p1v0 *
  page138_i34
#CELL
  pure_quanta iml3112y2b000ncg8 *
  page138_i35
#CELL
  pure_quanta q_cap *
  page138_i36
#ISCELL
  pure_quanta_power universal_gnd *
  page138_i37
#CELL
  pure_quanta q_res *
  page138_i38
#ISCELL
  pure_quanta_power universal_gnd *
  page138_i39
#ISCELL
  standard offpage *
  page138_i4
#CELL
  pure_quanta q_cap *
  page138_i40
#CELL
  pure_quanta q_res *
  page138_i41
#CELL
  pure_quanta q_res *
  page138_i42
#ISCELL
  standard offpage *
  page138_i43
#ISCELL
  standard offpage *
  page138_i44
#CELL
  pure_quanta q_res *
  page138_i46
#CELL
  pure_quanta q_res *
  page138_i48
#CELL
  pure_quanta q_res *
  page138_i5
#CELL
  pure_quanta q_res *
  page138_i50
#CELL
  pure_quanta q_res *
  page138_i52
#CELL
  pure_quanta q_res *
  page138_i54
#CELL
  pure_quanta q_res *
  page138_i56
#CELL
  pure_quanta q_res *
  page138_i58
#CELL
  pure_quanta q_res *
  page138_i6
#CELL
  pure_quanta q_res *
  page138_i60
#ISCELL
  pure_quanta_power vcc_core *
  page138_i63
#ISCELL
  pure_quanta_power vcc_core *
  page138_i64
#ISCELL
  standard offpage *
  page138_i65
#ISCELL
  standard offpage *
  page138_i66
#ISCELL
  standard offpage *
  page138_i67
#ISCELL
  standard offpage *
  page138_i68
#ISCELL
  standard offpage *
  page138_i69
#CELL
  pure_quanta q_res *
  page138_i7
#ISCELL
  standard offpage *
  page138_i70
#ISCELL
  standard offpage *
  page138_i71
#ISCELL
  standard offpage *
  page138_i72
#CELL
  pure_quanta q_res *
  page138_i73
#ISCELL
  pure_quanta_power universal_gnd *
  page138_i74
#CELL
  pure_quanta q_res *
  page138_i75
#ISCELL
  pure_quanta_power universal_gnd *
  page138_i76
#CELL
  pure_quanta q_res *
  page138_i8
#ISCELL
  pure_quanta_power universal_gnd *
  page138_i9
